(kicad_pcb
	(version 20260206)
	(generator "pcbnew")
	(generator_version "10.0")
	(general
		(thickness 1.6)
		(legacy_teardrops no)
	)
	(paper "A4")
	(title_block
		(title "03242023_DA0F0TMBIJ0_F0T_Motherboard_J_brd_V01_OCP.brd")
		(comment 1 "Grand Teton / footprints 2622-2627 of 6105")
	)
	(layers
		(0 "F.Cu" signal "TOP")
		(4 "In1.Cu" signal "GND")
		(6 "In2.Cu" signal "IN1")
		(8 "In3.Cu" signal "GND1")
		(10 "In4.Cu" signal "IN2")
		(12 "In5.Cu" signal "GND2")
		(14 "In6.Cu" signal "IN3")
		(16 "In7.Cu" signal "GND3")
		(18 "In8.Cu" signal "VCC")
		(20 "In9.Cu" signal "VCC1")
		(22 "In10.Cu" signal "GND4")
		(24 "In11.Cu" signal "IN4")
		(26 "In12.Cu" signal "GND5")
		(28 "In13.Cu" signal "IN5")
		(30 "In14.Cu" signal "GND6")
		(32 "In15.Cu" signal "IN6")
		(34 "In16.Cu" signal "GND7")
		(2 "B.Cu" signal "BOTTOM")
		(9 "F.Adhes" user "F.Adhesive")
		(11 "B.Adhes" user "B.Adhesive")
		(13 "F.Paste" user "Package Geometry/Pastemask Top")
		(15 "B.Paste" user "Package Geometry/Pastemask Bottom")
		(5 "F.SilkS" user "Ref Des/Silkscreen Top")
		(7 "B.SilkS" user "Ref Des/Silkscreen Bottom")
		(1 "F.Mask" user "Board Geometry/Soldermask Top")
		(3 "B.Mask" user "Board Geometry/Soldermask Bottom")
		(17 "Dwgs.User" user "User.Drawings")
		(19 "Cmts.User" user "User.Comments")
		(21 "Eco1.User" user "User.Eco1")
		(23 "Eco2.User" user "User.Eco2")
		(25 "Edge.Cuts" user "Board Geometry/Outline")
		(27 "Margin" user)
		(31 "F.CrtYd" user "Package Geometry/Place Bound Top")
		(29 "B.CrtYd" user "Package Geometry/Place Bound Bottom")
		(35 "F.Fab" user "Ref Des/Assembly Top")
		(33 "B.Fab" user "Ref Des/Assembly Bottom")
	)
	(footprint ""
		(layer "F.Cu")
		(at 332.124812 -18.797016 -90)
		(property "Reference" "R1255"
			(at 0 0 270)
			(layer "F.SilkS")
			(hide yes)
			(effects
				(font
					(size 1.27 1.27)
				)
			)
		)
		(property "Value" ""
			(at 0 0 270)
			(layer "F.Fab")
			(effects
				(font
					(size 1.27 1.27)
				)
			)
		)
		(duplicate_pad_numbers_are_jumpers no)
		(fp_line
			(start -0.7874 0.4064)
			(end -0.7874 -0.4064)
			(stroke
				(width 0.1524)
				(type default)
			)
			(layer "F.SilkS")
		)
		(fp_line
			(start 0.7874 0.4064)
			(end -0.7874 0.4064)
			(stroke
				(width 0.1524)
				(type default)
			)
			(layer "F.SilkS")
		)
		(fp_line
			(start -0.7874 -0.4064)
			(end 0.7874 -0.4064)
			(stroke
				(width 0.1524)
				(type default)
			)
			(layer "F.SilkS")
		)
		(fp_line
			(start 0.7874 -0.4064)
			(end 0.7874 0.4064)
			(stroke
				(width 0.1524)
				(type default)
			)
			(layer "F.SilkS")
		)
		(fp_line
			(start -0.67945 0.3048)
			(end -0.67945 -0.305054)
			(stroke
				(width 0.1)
				(type default)
			)
			(layer "F.Fab")
		)
		(fp_line
			(start -0.12065 0.3048)
			(end -0.67945 0.3048)
			(stroke
				(width 0.1)
				(type default)
			)
			(layer "F.Fab")
		)
		(fp_line
			(start 0.120396 0.3048)
			(end 0.120396 0.2794)
			(stroke
				(width 0.1)
				(type default)
			)
			(layer "F.Fab")
		)
		(fp_line
			(start 0.67945 0.3048)
			(end 0.120396 0.3048)
			(stroke
				(width 0.1)
				(type default)
			)
			(layer "F.Fab")
		)
		(fp_line
			(start -0.12065 0.2794)
			(end -0.12065 0.3048)
			(stroke
				(width 0.1)
				(type default)
			)
			(layer "F.Fab")
		)
		(fp_line
			(start 0.120396 0.2794)
			(end -0.12065 0.2794)
			(stroke
				(width 0.1)
				(type default)
			)
			(layer "F.Fab")
		)
		(fp_line
			(start -0.12065 -0.2794)
			(end 0.12065 -0.2794)
			(stroke
				(width 0.1)
				(type default)
			)
			(layer "F.Fab")
		)
		(fp_line
			(start 0.12065 -0.2794)
			(end 0.12065 -0.3048)
			(stroke
				(width 0.1)
				(type default)
			)
			(layer "F.Fab")
		)
		(fp_line
			(start 0.12065 -0.3048)
			(end 0.67945 -0.3048)
			(stroke
				(width 0.1)
				(type default)
			)
			(layer "F.Fab")
		)
		(fp_line
			(start 0.67945 -0.3048)
			(end 0.67945 0.3048)
			(stroke
				(width 0.1)
				(type default)
			)
			(layer "F.Fab")
		)
		(fp_line
			(start -0.67945 -0.305054)
			(end -0.12065 -0.305054)
			(stroke
				(width 0.1)
				(type default)
			)
			(layer "F.Fab")
		)
		(fp_line
			(start -0.12065 -0.305054)
			(end -0.12065 -0.2794)
			(stroke
				(width 0.1)
				(type default)
			)
			(layer "F.Fab")
		)
		(pad "1" smd circle
			(at -0.40005 0 270)
			(size 0 0)
			(layers "F.Cu" "F.Mask" "F.Paste")
			(net "PGPPA_AUX")
		)
		(pad "2" smd circle
			(at 0.40005 0 270)
			(size 0 0)
			(layers "F.Cu" "F.Mask" "F.Paste")
			(net "ESPI_ALERT1_N_LPC_RCIN_N")
		)
	)
	(footprint ""
		(layer "F.Cu")
		(at 145.175224 -95.643446 -90)
		(property "Reference" "C2248"
			(at 0 0 270)
			(layer "F.SilkS")
			(hide yes)
			(effects
				(font
					(size 1.27 1.27)
				)
			)
		)
		(property "Value" ""
			(at 0 0 270)
			(layer "F.Fab")
			(effects
				(font
					(size 1.27 1.27)
				)
			)
		)
		(duplicate_pad_numbers_are_jumpers no)
		(fp_line
			(start -0.7874 0.4064)
			(end -0.7874 -0.4064)
			(stroke
				(width 0.1524)
				(type default)
			)
			(layer "F.SilkS")
		)
		(fp_line
			(start 0.7874 0.4064)
			(end -0.7874 0.4064)
			(stroke
				(width 0.1524)
				(type default)
			)
			(layer "F.SilkS")
		)
		(fp_line
			(start -0.7874 -0.4064)
			(end 0.7874 -0.4064)
			(stroke
				(width 0.1524)
				(type default)
			)
			(layer "F.SilkS")
		)
		(fp_line
			(start 0.7874 -0.4064)
			(end 0.7874 0.4064)
			(stroke
				(width 0.1524)
				(type default)
			)
			(layer "F.SilkS")
		)
		(fp_line
			(start -0.67945 0.3048)
			(end -0.67945 -0.305054)
			(stroke
				(width 0.1)
				(type default)
			)
			(layer "F.Fab")
		)
		(fp_line
			(start -0.12065 0.3048)
			(end -0.67945 0.3048)
			(stroke
				(width 0.1)
				(type default)
			)
			(layer "F.Fab")
		)
		(fp_line
			(start 0.120396 0.3048)
			(end 0.120396 0.2794)
			(stroke
				(width 0.1)
				(type default)
			)
			(layer "F.Fab")
		)
		(fp_line
			(start 0.67945 0.3048)
			(end 0.120396 0.3048)
			(stroke
				(width 0.1)
				(type default)
			)
			(layer "F.Fab")
		)
		(fp_line
			(start -0.12065 0.2794)
			(end -0.12065 0.3048)
			(stroke
				(width 0.1)
				(type default)
			)
			(layer "F.Fab")
		)
		(fp_line
			(start 0.120396 0.2794)
			(end -0.12065 0.2794)
			(stroke
				(width 0.1)
				(type default)
			)
			(layer "F.Fab")
		)
		(fp_line
			(start -0.12065 -0.2794)
			(end 0.12065 -0.2794)
			(stroke
				(width 0.1)
				(type default)
			)
			(layer "F.Fab")
		)
		(fp_line
			(start 0.12065 -0.2794)
			(end 0.12065 -0.3048)
			(stroke
				(width 0.1)
				(type default)
			)
			(layer "F.Fab")
		)
		(fp_line
			(start 0.12065 -0.3048)
			(end 0.67945 -0.3048)
			(stroke
				(width 0.1)
				(type default)
			)
			(layer "F.Fab")
		)
		(fp_line
			(start 0.67945 -0.3048)
			(end 0.67945 0.3048)
			(stroke
				(width 0.1)
				(type default)
			)
			(layer "F.Fab")
		)
		(fp_line
			(start -0.67945 -0.305054)
			(end -0.12065 -0.305054)
			(stroke
				(width 0.1)
				(type default)
			)
			(layer "F.Fab")
		)
		(fp_line
			(start -0.12065 -0.305054)
			(end -0.12065 -0.2794)
			(stroke
				(width 0.1)
				(type default)
			)
			(layer "F.Fab")
		)
		(pad "1" smd circle
			(at -0.40005 0 270)
			(size 0 0)
			(layers "F.Cu" "F.Mask" "F.Paste")
			(net "P3V3")
		)
		(pad "2" smd circle
			(at 0.40005 0 270)
			(size 0 0)
			(layers "F.Cu" "F.Mask" "F.Paste")
			(net "GND")
		)
	)
	(footprint ""
		(layer "F.Cu")
		(at 115.95608 -119.846598 -90)
		(property "Reference" "R853"
			(at 0 0 270)
			(layer "F.SilkS")
			(hide yes)
			(effects
				(font
					(size 1.27 1.27)
				)
			)
		)
		(property "Value" ""
			(at 0 0 270)
			(layer "F.Fab")
			(effects
				(font
					(size 1.27 1.27)
				)
			)
		)
		(duplicate_pad_numbers_are_jumpers no)
		(fp_line
			(start -0.7874 0.4064)
			(end -0.7874 -0.4064)
			(stroke
				(width 0.1524)
				(type default)
			)
			(layer "F.SilkS")
		)
		(fp_line
			(start 0.7874 0.4064)
			(end -0.7874 0.4064)
			(stroke
				(width 0.1524)
				(type default)
			)
			(layer "F.SilkS")
		)
		(fp_line
			(start -0.7874 -0.4064)
			(end 0.7874 -0.4064)
			(stroke
				(width 0.1524)
				(type default)
			)
			(layer "F.SilkS")
		)
		(fp_line
			(start 0.7874 -0.4064)
			(end 0.7874 0.4064)
			(stroke
				(width 0.1524)
				(type default)
			)
			(layer "F.SilkS")
		)
		(fp_line
			(start -0.67945 0.3048)
			(end -0.67945 -0.305054)
			(stroke
				(width 0.1)
				(type default)
			)
			(layer "F.Fab")
		)
		(fp_line
			(start -0.12065 0.3048)
			(end -0.67945 0.3048)
			(stroke
				(width 0.1)
				(type default)
			)
			(layer "F.Fab")
		)
		(fp_line
			(start 0.120396 0.3048)
			(end 0.120396 0.2794)
			(stroke
				(width 0.1)
				(type default)
			)
			(layer "F.Fab")
		)
		(fp_line
			(start 0.67945 0.3048)
			(end 0.120396 0.3048)
			(stroke
				(width 0.1)
				(type default)
			)
			(layer "F.Fab")
		)
		(fp_line
			(start -0.12065 0.2794)
			(end -0.12065 0.3048)
			(stroke
				(width 0.1)
				(type default)
			)
			(layer "F.Fab")
		)
		(fp_line
			(start 0.120396 0.2794)
			(end -0.12065 0.2794)
			(stroke
				(width 0.1)
				(type default)
			)
			(layer "F.Fab")
		)
		(fp_line
			(start -0.12065 -0.2794)
			(end 0.12065 -0.2794)
			(stroke
				(width 0.1)
				(type default)
			)
			(layer "F.Fab")
		)
		(fp_line
			(start 0.12065 -0.2794)
			(end 0.12065 -0.3048)
			(stroke
				(width 0.1)
				(type default)
			)
			(layer "F.Fab")
		)
		(fp_line
			(start 0.12065 -0.3048)
			(end 0.67945 -0.3048)
			(stroke
				(width 0.1)
				(type default)
			)
			(layer "F.Fab")
		)
		(fp_line
			(start 0.67945 -0.3048)
			(end 0.67945 0.3048)
			(stroke
				(width 0.1)
				(type default)
			)
			(layer "F.Fab")
		)
		(fp_line
			(start -0.67945 -0.305054)
			(end -0.12065 -0.305054)
			(stroke
				(width 0.1)
				(type default)
			)
			(layer "F.Fab")
		)
		(fp_line
			(start -0.12065 -0.305054)
			(end -0.12065 -0.2794)
			(stroke
				(width 0.1)
				(type default)
			)
			(layer "F.Fab")
		)
		(pad "1" smd circle
			(at -0.40005 0 270)
			(size 0 0)
			(layers "F.Cu" "F.Mask" "F.Paste")
			(net "RST_CPU0_DRAM_EF_N")
		)
		(pad "2" smd circle
			(at 0.40005 0 270)
			(size 0 0)
			(layers "F.Cu" "F.Mask" "F.Paste")
			(net "RST_CPU0_DRAM_EF_PLD_N")
		)
	)
	(footprint ""
		(layer "F.Cu")
		(at 412.585662 -361.896914 -90)
		(property "Reference" "PC1211_P0_1"
			(at 0 0 270)
			(layer "F.SilkS")
			(hide yes)
			(effects
				(font
					(size 1.27 1.27)
				)
			)
		)
		(property "Value" ""
			(at 0 0 270)
			(layer "F.Fab")
			(effects
				(font
					(size 1.27 1.27)
				)
			)
		)
		(duplicate_pad_numbers_are_jumpers no)
		(fp_line
			(start -0.7874 0.4064)
			(end -0.7874 -0.4064)
			(stroke
				(width 0.1524)
				(type default)
			)
			(layer "F.SilkS")
		)
		(fp_line
			(start 0.7874 0.4064)
			(end -0.7874 0.4064)
			(stroke
				(width 0.1524)
				(type default)
			)
			(layer "F.SilkS")
		)
		(fp_line
			(start -0.7874 -0.4064)
			(end 0.7874 -0.4064)
			(stroke
				(width 0.1524)
				(type default)
			)
			(layer "F.SilkS")
		)
		(fp_line
			(start 0.7874 -0.4064)
			(end 0.7874 0.4064)
			(stroke
				(width 0.1524)
				(type default)
			)
			(layer "F.SilkS")
		)
		(fp_line
			(start -0.67945 0.3048)
			(end -0.67945 -0.305054)
			(stroke
				(width 0.1)
				(type default)
			)
			(layer "F.Fab")
		)
		(fp_line
			(start -0.12065 0.3048)
			(end -0.67945 0.3048)
			(stroke
				(width 0.1)
				(type default)
			)
			(layer "F.Fab")
		)
		(fp_line
			(start 0.120396 0.3048)
			(end 0.120396 0.2794)
			(stroke
				(width 0.1)
				(type default)
			)
			(layer "F.Fab")
		)
		(fp_line
			(start 0.67945 0.3048)
			(end 0.120396 0.3048)
			(stroke
				(width 0.1)
				(type default)
			)
			(layer "F.Fab")
		)
		(fp_line
			(start -0.12065 0.2794)
			(end -0.12065 0.3048)
			(stroke
				(width 0.1)
				(type default)
			)
			(layer "F.Fab")
		)
		(fp_line
			(start 0.120396 0.2794)
			(end -0.12065 0.2794)
			(stroke
				(width 0.1)
				(type default)
			)
			(layer "F.Fab")
		)
		(fp_line
			(start -0.12065 -0.2794)
			(end 0.12065 -0.2794)
			(stroke
				(width 0.1)
				(type default)
			)
			(layer "F.Fab")
		)
		(fp_line
			(start 0.12065 -0.2794)
			(end 0.12065 -0.3048)
			(stroke
				(width 0.1)
				(type default)
			)
			(layer "F.Fab")
		)
		(fp_line
			(start 0.12065 -0.3048)
			(end 0.67945 -0.3048)
			(stroke
				(width 0.1)
				(type default)
			)
			(layer "F.Fab")
		)
		(fp_line
			(start 0.67945 -0.3048)
			(end 0.67945 0.3048)
			(stroke
				(width 0.1)
				(type default)
			)
			(layer "F.Fab")
		)
		(fp_line
			(start -0.67945 -0.305054)
			(end -0.12065 -0.305054)
			(stroke
				(width 0.1)
				(type default)
			)
			(layer "F.Fab")
		)
		(fp_line
			(start -0.12065 -0.305054)
			(end -0.12065 -0.2794)
			(stroke
				(width 0.1)
				(type default)
			)
			(layer "F.Fab")
		)
		(pad "1" smd circle
			(at -0.40005 0 270)
			(size 0 0)
			(layers "F.Cu" "F.Mask" "F.Paste")
			(net "PVCCFA_EHV_FIVRA_CPU0_PVCC1")
		)
		(pad "2" smd circle
			(at 0.40005 0 270)
			(size 0 0)
			(layers "F.Cu" "F.Mask" "F.Paste")
			(net "GND")
		)
	)
	(footprint ""
		(layer "F.Cu")
		(at 315.10224 -48.584866)
		(property "Reference" "R699"
			(at 0 0 0)
			(layer "F.SilkS")
			(hide yes)
			(effects
				(font
					(size 1.27 1.27)
				)
			)
		)
		(property "Value" ""
			(at 0 0 0)
			(layer "F.Fab")
			(effects
				(font
					(size 1.27 1.27)
				)
			)
		)
		(duplicate_pad_numbers_are_jumpers no)
		(fp_line
			(start -0.7874 -0.4064)
			(end 0.7874 -0.4064)
			(stroke
				(width 0.1524)
				(type default)
			)
			(layer "F.SilkS")
		)
		(fp_line
			(start -0.7874 0.4064)
			(end -0.7874 -0.4064)
			(stroke
				(width 0.1524)
				(type default)
			)
			(layer "F.SilkS")
		)
		(fp_line
			(start 0.7874 -0.4064)
			(end 0.7874 0.4064)
			(stroke
				(width 0.1524)
				(type default)
			)
			(layer "F.SilkS")
		)
		(fp_line
			(start 0.7874 0.4064)
			(end -0.7874 0.4064)
			(stroke
				(width 0.1524)
				(type default)
			)
			(layer "F.SilkS")
		)
		(fp_line
			(start -0.67945 -0.305054)
			(end -0.12065 -0.305054)
			(stroke
				(width 0.1)
				(type default)
			)
			(layer "F.Fab")
		)
		(fp_line
			(start -0.67945 0.3048)
			(end -0.67945 -0.305054)
			(stroke
				(width 0.1)
				(type default)
			)
			(layer "F.Fab")
		)
		(fp_line
			(start -0.12065 -0.305054)
			(end -0.12065 -0.2794)
			(stroke
				(width 0.1)
				(type default)
			)
			(layer "F.Fab")
		)
		(fp_line
			(start -0.12065 -0.2794)
			(end 0.12065 -0.2794)
			(stroke
				(width 0.1)
				(type default)
			)
			(layer "F.Fab")
		)
		(fp_line
			(start -0.12065 0.2794)
			(end -0.12065 0.3048)
			(stroke
				(width 0.1)
				(type default)
			)
			(layer "F.Fab")
		)
		(fp_line
			(start -0.12065 0.3048)
			(end -0.67945 0.3048)
			(stroke
				(width 0.1)
				(type default)
			)
			(layer "F.Fab")
		)
		(fp_line
			(start 0.120396 0.2794)
			(end -0.12065 0.2794)
			(stroke
				(width 0.1)
				(type default)
			)
			(layer "F.Fab")
		)
		(fp_line
			(start 0.120396 0.3048)
			(end 0.120396 0.2794)
			(stroke
				(width 0.1)
				(type default)
			)
			(layer "F.Fab")
		)
		(fp_line
			(start 0.12065 -0.3048)
			(end 0.67945 -0.3048)
			(stroke
				(width 0.1)
				(type default)
			)
			(layer "F.Fab")
		)
		(fp_line
			(start 0.12065 -0.2794)
			(end 0.12065 -0.3048)
			(stroke
				(width 0.1)
				(type default)
			)
			(layer "F.Fab")
		)
		(fp_line
			(start 0.67945 -0.3048)
			(end 0.67945 0.3048)
			(stroke
				(width 0.1)
				(type default)
			)
			(layer "F.Fab")
		)
		(fp_line
			(start 0.67945 0.3048)
			(end 0.120396 0.3048)
			(stroke
				(width 0.1)
				(type default)
			)
			(layer "F.Fab")
		)
		(pad "1" smd circle
			(at -0.40005 0)
			(size 0 0)
			(layers "F.Cu" "F.Mask" "F.Paste")
			(net "FM_PCH_CRASHLOG_TRIG_R_N")
		)
		(pad "2" smd circle
			(at 0.40005 0)
			(size 0 0)
			(layers "F.Cu" "F.Mask" "F.Paste")
			(net "FM_PCH_CRASHLOG_TRIG_N")
		)
	)
	(footprint ""
		(layer "F.Cu")
		(at 299.02023 -54.400196)
		(property "Reference" "R2976"
			(at 0 0 0)
			(layer "F.SilkS")
			(hide yes)
			(effects
				(font
					(size 1.27 1.27)
				)
			)
		)
		(property "Value" ""
			(at 0 0 0)
			(layer "F.Fab")
			(effects
				(font
					(size 1.27 1.27)
				)
			)
		)
		(duplicate_pad_numbers_are_jumpers no)
		(fp_line
			(start -0.7874 -0.4064)
			(end 0.7874 -0.4064)
			(stroke
				(width 0.1524)
				(type default)
			)
			(layer "F.SilkS")
		)
		(fp_line
			(start -0.7874 0.4064)
			(end -0.7874 -0.4064)
			(stroke
				(width 0.1524)
				(type default)
			)
			(layer "F.SilkS")
		)
		(fp_line
			(start 0.7874 -0.4064)
			(end 0.7874 0.4064)
			(stroke
				(width 0.1524)
				(type default)
			)
			(layer "F.SilkS")
		)
		(fp_line
			(start 0.7874 0.4064)
			(end -0.7874 0.4064)
			(stroke
				(width 0.1524)
				(type default)
			)
			(layer "F.SilkS")
		)
		(fp_line
			(start -0.67945 -0.305054)
			(end -0.12065 -0.305054)
			(stroke
				(width 0.1)
				(type default)
			)
			(layer "F.Fab")
		)
		(fp_line
			(start -0.67945 0.3048)
			(end -0.67945 -0.305054)
			(stroke
				(width 0.1)
				(type default)
			)
			(layer "F.Fab")
		)
		(fp_line
			(start -0.12065 -0.305054)
			(end -0.12065 -0.2794)
			(stroke
				(width 0.1)
				(type default)
			)
			(layer "F.Fab")
		)
		(fp_line
			(start -0.12065 -0.2794)
			(end 0.12065 -0.2794)
			(stroke
				(width 0.1)
				(type default)
			)
			(layer "F.Fab")
		)
		(fp_line
			(start -0.12065 0.2794)
			(end -0.12065 0.3048)
			(stroke
				(width 0.1)
				(type default)
			)
			(layer "F.Fab")
		)
		(fp_line
			(start -0.12065 0.3048)
			(end -0.67945 0.3048)
			(stroke
				(width 0.1)
				(type default)
			)
			(layer "F.Fab")
		)
		(fp_line
			(start 0.120396 0.2794)
			(end -0.12065 0.2794)
			(stroke
				(width 0.1)
				(type default)
			)
			(layer "F.Fab")
		)
		(fp_line
			(start 0.120396 0.3048)
			(end 0.120396 0.2794)
			(stroke
				(width 0.1)
				(type default)
			)
			(layer "F.Fab")
		)
		(fp_line
			(start 0.12065 -0.3048)
			(end 0.67945 -0.3048)
			(stroke
				(width 0.1)
				(type default)
			)
			(layer "F.Fab")
		)
		(fp_line
			(start 0.12065 -0.2794)
			(end 0.12065 -0.3048)
			(stroke
				(width 0.1)
				(type default)
			)
			(layer "F.Fab")
		)
		(fp_line
			(start 0.67945 -0.3048)
			(end 0.67945 0.3048)
			(stroke
				(width 0.1)
				(type default)
			)
			(layer "F.Fab")
		)
		(fp_line
			(start 0.67945 0.3048)
			(end 0.120396 0.3048)
			(stroke
				(width 0.1)
				(type default)
			)
			(layer "F.Fab")
		)
		(pad "1" smd circle
			(at -0.40005 0)
			(size 0 0)
			(layers "F.Cu" "F.Mask" "F.Paste")
			(net "P1V05_PCH_AUX")
		)
		(pad "2" smd circle
			(at 0.40005 0)
			(size 0 0)
			(layers "F.Cu" "F.Mask" "F.Paste")
			(net "FM_BOARD_SKU_ID3")
		)
	)
)
